FILE_TYPE = CONNECTIVITY;
{Allegro Design Entry HDL 17.2-2016 S066 (3851973) 4/6/2020}
"PAGE_NUMBER" = 515;
0"NC";
1"XP3R3V\g";
2"SG\g";
3"XP3R3V_FPGA\g";
4"XP3R3V_FPGA\g";
5"SG\g";
6"SG\g";
7"XP3R3V\g";
8"XP3R3V\g";
9"SG\g";
10"XP3R3V_FPGA\g";
11"SG\g";
12"SG\g";
13"SG\g";
14"SG\g";
15"XP2R5V_FPGA\g";
16"SG\g";
17"SG\g";
18"SG\g";
19"SG\g";
20"SG\g";
21"XP3R3V\g";
22"UN$515$CAPACITOR$I128$1";
23"UN$515$CAPACITOR$I132$1";
24"UN$515$CAPACITOR$I130$1";
25"XP3R3V_FPGA_SR";
26"FPGA_CFG_INIT_N";
27"FPGA_CFG_INIT_N";
28"UN$515$CAPACITOR$I138$1";
29"UN$515$ISL80101IRAJZDFN10$I151$SENSE";
30"XP3R3V_FPGA_EN_R";
31"XP1R8V_FPGA_PG";
32"XP1R8V_FPGA_PG";
33"UN$515$NCP45560IMNTWGHDFN12$I82$PG";
%"RESISTOR"
"1","(-10700,6600)","0","passive","I122";
;
$LOCATION"R226"
CDS_LOCATION"R226"
$SEC"1"
CDS_SEC"1"
PACKAGE"0402"
VALUE"330OHM"
TOLERANCE"1%"
CLS_PN"G155-13300-01"
CDS_LIB"passive"
CDS_LMAN_SYM_OUTLINE"-50,50,100,-50";
"1"
$PN"1"31;
"2"
$PN"2"30;
%"VCC"
"1","(-11350,2300)","0","cls","I124";
;
VOLTAGE"3.3"
HDL_POWER"XP3R3V"
CDS_LMAN_SYM_OUTLINE"-250,250,250,-250"
CDS_LIB"cls"
BODY_TYPE"PLUMBING";
"$PIN0"21;
%"GND_SG"
"1","(-10200,300)","0","cls","I126";
;
HDL_POWER"SG"
CDS_LIB"cls"
CDS_LMAN_SYM_OUTLINE"0,0,100,-50"
BODY_TYPE"PLUMBING";
"SGND"20;
%"RESISTOR"
"2","(-9800,850)","0","passive","I127";
;
$LOCATION"R227"
CDS_LOCATION"R227"
$SEC"1"
CDS_SEC"1"
PACKAGE"0402"
NO_ASSY"TRUE"
VALUE"10KOHM"
CLS_PN"G155-11002-01"
CDS_LMAN_SYM_OUTLINE"-50,50,50,-100"
CDS_LIB"passive"
TOLERANCE"1%";
"1"
$PN"1"22;
"2"
$PN"2"20;
%"CAPACITOR"
"2","(-9250,800)","0","passive","I128";
;
$LOCATION"C227"
CDS_LOCATION"C227"
$SEC"1"
CDS_SEC"1"
PACKAGE"0402"
VOLTAGE"25V"
VALUE"0.1UF"
CLS_PN"G105-0B104-EK"
CDS_LMAN_SYM_OUTLINE"-50,0,50,-50"
CDS_LIB"passive"
TOLERANCE"10%";
"2"
$PN"2"20;
"1"
$PN"1"22;
%"RESISTOR"
"2","(-9750,1700)","0","passive","I129";
;
$LOCATION"R228"
CDS_LOCATION"R228"
$SEC"1"
CDS_SEC"1"
PACKAGE"0402"
VALUE"1.13KOHM"
NO_ASSY"TRUE"
CDS_LIB"passive"
CDS_LMAN_SYM_OUTLINE"-50,50,50,-100"
CLS_PN"G152-00055-01"
TOLERANCE"1%";
"1"
$PN"1"24;
"2"
$PN"2"22;
%"CAPACITOR"
"2","(-9300,1850)","0","passive","I130";
;
$LOCATION"C228"
CDS_LOCATION"C228"
$SEC"1"
CDS_SEC"1"
PACKAGE"0805"
VOLTAGE"25V"
VALUE"10UF"
CLS_PN"G107-0F106-EM"
TOLERANCE"20%"
CDS_LIB"passive"
CDS_LMAN_SYM_OUTLINE"-50,0,50,-50";
"2"
$PN"2"19;
"1"
$PN"1"24;
%"GND_SG"
"1","(-8800,250)","0","cls","I131";
;
VOLTAGE"0"
HDL_POWER"SG"
CDS_LIB"cls"
CDS_LMAN_SYM_OUTLINE"0,0,100,-50"
BODY_TYPE"PLUMBING";
"SGND"6;
%"CAPACITOR"
"2","(-8750,650)","0","passive","I132";
;
$LOCATION"C231"
CDS_LOCATION"C231"
$SEC"1"
CDS_SEC"1"
PACKAGE"0201"
VALUE"0.01UF"
VOLTAGE"25V"
CLS_PN"G104-0B103-EK"
TOLERANCE"10%"
CDS_LIB"passive"
CDS_LMAN_SYM_OUTLINE"-50,0,50,-50";
"2"
$PN"2"6;
"1"
$PN"1"23;
%"GND_SG"
"1","(-8900,1400)","0","cls","I133";
;
VOLTAGE"0"
HDL_POWER"SG"
CDS_LIB"cls"
CDS_LMAN_SYM_OUTLINE"0,0,100,-50"
BODY_TYPE"PLUMBING";
"SGND"19;
%"CAPACITOR"
"2","(-8850,1850)","0","passive","I134";
;
$LOCATION"C230"
CDS_LOCATION"C230"
$SEC"1"
CDS_SEC"1"
PACKAGE"0402"
VOLTAGE"25V"
VALUE"0.1UF"
TOLERANCE"10%"
CDS_LIB"passive"
CDS_LMAN_SYM_OUTLINE"-50,0,50,-50"
CLS_PN"G105-0B104-EK";
"2"
$PN"2"19;
"1"
$PN"1"24;
%"FERRITEBEAD"
"1","(-10550,2200)","0","passive","I135";
;
$LOCATION"L13"
CDS_LOCATION"L13"
$SEC"1"
CDS_SEC"1"
PACKAGE"0603"
VALUE"26OHM"
CDS_LIB"passive"
CDS_LMAN_SYM_OUTLINE"0,0,200,-100"
CLS_PN"G191-10101-01"
TOLERANCE"25%";
"2"
$PN"2"24;
"1"
$PN"1"21;
%"GND_SG"
"1","(-6700,100)","0","cls","I136";
;
VOLTAGE"0"
HDL_POWER"SG"
CDS_LIB"cls"
CDS_LMAN_SYM_OUTLINE"0,0,100,-50"
BODY_TYPE"PLUMBING";
"SGND"18;
%"GND_SG"
"1","(-5850,-200)","0","cls","I137";
;
VOLTAGE"0"
HDL_POWER"SG"
CDS_LMAN_SYM_OUTLINE"0,0,100,-50"
CDS_LIB"cls"
BODY_TYPE"PLUMBING";
"SGND"5;
%"CAPACITOR"
"2","(-5800,50)","0","passive","I138";
;
$LOCATION"C234"
CDS_LOCATION"C234"
$SEC"1"
CDS_SEC"1"
VALUE"0.01UF"
PACKAGE"0201"
VOLTAGE"25V"
CLS_PN"G104-0B103-EK"
TOLERANCE"10%"
CDS_LMAN_SYM_OUTLINE"-50,0,50,-50"
CDS_LIB"passive";
"2"
$PN"2"5;
"1"
$PN"1"28;
%"RESISTOR"
"2","(-5750,550)","0","passive","I139";
;
$LOCATION"R229"
CDS_LOCATION"R229"
$SEC"1"
CDS_SEC"1"
VALUE"4.7KOHM"
PACKAGE"0402"
NO_ASSY"TRUE"
CLS_PN"G155-14701-01"
CDS_LMAN_SYM_OUTLINE"-50,50,50,-100"
CDS_LIB"passive"
TOLERANCE"1%";
"1"
$PN"1"3;
"2"
$PN"2"28;
%"RESISTOR"
"1","(-5050,250)","0","passive","I140";
;
$LOCATION"R230"
CDS_LOCATION"R230"
$SEC"1"
CDS_SEC"1"
VALUE"0OHM"
CLS_PN"G155-100R0-J0"
CDS_LMAN_SYM_OUTLINE"-50,50,100,-50"
CDS_LIB"passive"
TOLERANCE"-";
"1"
$PN"1"28;
"2"
$PN"2"27;
%"RESISTOR"
"1","(-4400,1050)","1","passive","I143";
;
$LOCATION"R232"
CDS_LOCATION"R232"
$SEC"1"
CDS_SEC"1"
VALUE"2.1KOHM"
PACKAGE"0402"
CDS_LIB"passive"
CDS_LMAN_SYM_OUTLINE"-50,50,100,-50"
CLS_PN"G155-02101-01"
TOLERANCE"1%";
"1"
$PN"1"17;
"2"
$PN"2"29;
%"GND_SG"
"1","(-4200,700)","0","cls","I144";
;
HDL_POWER"SG"
CDS_LIB"cls"
CDS_LMAN_SYM_OUTLINE"0,0,100,-50"
BODY_TYPE"PLUMBING";
"SGND"17;
%"RESISTOR"
"1","(-4150,1050)","1","passive","I145";
;
$LOCATION"R233"
CDS_LOCATION"R233"
$SEC"1"
CDS_SEC"1"
PACKAGE"0402"
VALUE"2.1KOHM"
CLS_PN"G155-02101-01"
CDS_LMAN_SYM_OUTLINE"-50,50,100,-50"
CDS_LIB"passive"
TOLERANCE"1%";
"1"
$PN"1"17;
"2"
$PN"2"29;
%"RESISTOR"
"2","(-4450,1750)","0","passive","I146";
;
$LOCATION"R231"
CDS_LOCATION"R231"
$SEC"1"
CDS_SEC"1"
VALUE"4.22KOHM"
PACKAGE"0402"
TOLERANCE"1%"
CDS_LIB"passive"
CDS_LMAN_SYM_OUTLINE"-50,50,50,-100"
CLS_PN"G155-04221-01";
"1"
$PN"1"15;
"2"
$PN"2"29;
%"CAPACITOR"
"2","(-3800,1750)","0","passive","I147";
;
$LOCATION"C239"
CDS_LOCATION"C239"
$SEC"1"
CDS_SEC"1"
VOLTAGE"25V"
VALUE"10UF"
PACKAGE"0805"
CLS_PN"G107-0F106-EM"
TOLERANCE"20%"
CDS_LIB"passive"
CDS_LMAN_SYM_OUTLINE"-50,0,50,-50";
"2"
$PN"2"16;
"1"
$PN"1"15;
%"GND_SG"
"1","(-3250,1100)","0","cls","I148";
;
HDL_POWER"SG"
CDS_LIB"cls"
CDS_LMAN_SYM_OUTLINE"0,0,100,-50"
BODY_TYPE"PLUMBING";
"SGND"16;
%"CAPACITOR"
"2","(-3200,1750)","0","passive","I149";
;
$LOCATION"C242"
CDS_LOCATION"C242"
$SEC"1"
CDS_SEC"1"
VALUE"0.1UF"
VOLTAGE"25V"
PACKAGE"0805"
TOLERANCE"10%"
CDS_LIB"passive"
CDS_LMAN_SYM_OUTLINE"-50,0,50,-50"
CLS_PN"G105-0B104-EK";
"2"
$PN"2"16;
"1"
$PN"1"15;
%"VCC"
"1","(-2400,2300)","0","cls","I150";
;
VOLTAGE"2.5V"
HDL_POWER"XP2R5V_FPGA"
CDS_LIB"cls"
CDS_LMAN_SYM_OUTLINE"-250,250,250,-250"
BODY_TYPE"PLUMBING";
"$PIN0"15;
%"ISL80101IRAJZ_DFN10"
"1","(-7950,1750)","0","analog","I151";
;
$LOCATION"U25"
CDS_LOCATION"U25"
$SEC"1"
CDS_SEC"1"
CLS_PN"G222-10136-01"
PART_NUMBER"ISL80101IRAJZ-T"
CDS_LIB"analog"
CDS_LMAN_SYM_OUTLINE"0,0,900,-1000";
"THRM_PAD"
$PN"11"18;
"VIN_2"
$PN"10"24;
"VIN_1"
$PN"9"24;
"NC"
$PN"8"0;
"ENABLE"
$PN"7"22;
"SS"
$PN"6"23;
"GND"
$PN"5"18;
"PG"
$PN"4"28;
"SENSE/ADJ"
$PN"3"29;
"VOUT_2"
$PN"2"15;
"VOUT_1"
$PN"1"15;
%"RESISTOR"
"1","(-10900,1150)","0","passive","I152";
;
$LOCATION"R225"
CDS_LOCATION"R225"
$SEC"1"
CDS_SEC"1"
PACKAGE"0402"
VALUE"330OHM"
CDS_LIB"passive"
CDS_LMAN_SYM_OUTLINE"-50,50,100,-50"
CLS_PN"G155-13300-01"
TOLERANCE"1%";
"1"
$PN"1"32;
"2"
$PN"2"22;
%"GND_SG"
"1","(-10800,1500)","0","cls","I153";
;
HDL_POWER"SG"
CDS_LIB"cls"
CDS_LMAN_SYM_OUTLINE"0,0,100,-50"
BODY_TYPE"PLUMBING";
"SGND"14;
%"CAPACITOR"
"2","(-11200,1850)","0","passive","I154";
;
$LOCATION"C224"
CDS_LOCATION"C224"
$SEC"1"
CDS_SEC"1"
PACKAGE"0805"
VALUE"22UF"
VOLTAGE"10V"
TOLERANCE"20%"
CLS_PN"G107-0F226-CM"
CDS_LMAN_SYM_OUTLINE"-50,0,50,-50"
CDS_LIB"passive";
"2"
$PN"2"14;
"1"
$PN"1"21;
%"CAPACITOR"
"2","(-10750,1850)","0","passive","I155";
;
$LOCATION"C226"
CDS_LOCATION"C226"
$SEC"1"
CDS_SEC"1"
VOLTAGE"25V"
PACKAGE"0402"
VALUE"0.1UF"
TOLERANCE"10%"
CLS_PN"G105-0B104-EK"
MATERIAL"X7R"
CDS_LMAN_SYM_OUTLINE"-50,0,50,-50"
CDS_LIB"passive";
"2"
$PN"2"14;
"1"
$PN"1"21;
%"VCC"
"1","(-6150,7400)","0","cls","I163";
;
VOLTAGE"3.3V"
HDL_POWER"XP3R3V_FPGA"
CDS_LMAN_SYM_OUTLINE"-250,250,250,-250"
CDS_LIB"cls"
BODY_TYPE"PLUMBING";
"$PIN0"4;
%"VCC"
"1","(-5800,800)","0","cls","I164";
;
VOLTAGE"3.3V"
HDL_POWER"XP3R3V_FPGA"
CDS_LIB"cls"
CDS_LMAN_SYM_OUTLINE"-250,250,250,-250"
BODY_TYPE"PLUMBING";
"$PIN0"3;
%"RESISTOR"
"1","(-6650,6400)","0","passive","I167";
;
$LOCATION"R143"
CDS_LOCATION"R143"
$SEC"1"
CDS_SEC"1"
PACKAGE"0402"
VALUE"33OHM"
SIGNAL_MODEL"DEFAULT_RESISTOR_33OHM_2_1"
CDS_LMAN_SYM_OUTLINE"-50,50,100,-50"
CDS_LIB"passive"
CLS_PN"G155-133R0-01"
TOLERANCE"1%";
"1"
$PN"1"26;
"2"
$PN"2"33;
%"CAPACITOR"
"2","(-10150,800)","0","passive","I168";
;
$LOCATION"C293"
CDS_LOCATION"C293"
$SEC"1"
CDS_SEC"1"
VALUE"0.22UF"
VOLTAGE"25V"
PACKAGE"0402"
CDS_LIB"passive"
CDS_LMAN_SYM_OUTLINE"-50,0,50,-50"
TOLERANCE"10%"
CLS_PN"G105-0B224-DK";
"2"
$PN"2"20;
"1"
$PN"1"22;
%"CAPACITOR"
"2","(-10100,6300)","0","passive","I169";
;
$LOCATION"C294"
CDS_LOCATION"C294"
$SEC"1"
CDS_SEC"1"
VOLTAGE"25V"
VALUE"0.22UF"
PACKAGE"0402"
CLS_PN"G105-0B224-DK"
TOLERANCE"10%"
CDS_LIB"passive"
CDS_LMAN_SYM_OUTLINE"-50,0,50,-50";
"2"
$PN"2"13;
"1"
$PN"1"30;
%"GND_SG"
"1","(-10150,5700)","0","cls","I55";
;
HDL_POWER"SG"
BODY_TYPE"PLUMBING"
CDS_LMAN_SYM_OUTLINE"0,0,100,-50"
CDS_LIB"cls";
"SGND"13;
%"RESISTOR"
"2","(-9650,6250)","0","passive","I56";
;
$LOCATION"R237"
CDS_LOCATION"R237"
$SEC"1"
CDS_SEC"1"
NO_ASSY"TRUE"
VALUE"10KOHM"
PACKAGE"0402"
CDS_LMAN_SYM_OUTLINE"-50,50,50,-100"
CDS_LIB"passive"
CLS_PN"G155-11002-01"
TOLERANCE"1%";
"1"
$PN"1"30;
"2"
$PN"2"13;
%"GND_SG"
"1","(-7850,4700)","0","cls","I60";
;
HDL_POWER"SG"
CDS_LIB"cls"
CDS_LMAN_SYM_OUTLINE"0,0,100,-50"
BODY_TYPE"PLUMBING";
"SGND"12;
%"CAPACITOR"
"2","(-7800,5400)","0","passive","I61";
;
$LOCATION"C232"
CDS_LOCATION"C232"
$SEC"1"
CDS_SEC"1"
VOLTAGE"10V"
PACKAGE"0805"
VALUE"22UF"
TOLERANCE"20%"
CLS_PN"G107-0F226-CM"
CDS_LMAN_SYM_OUTLINE"-50,0,50,-50"
CDS_LIB"passive";
"2"
$PN"2"12;
"1"
$PN"1"7;
%"CAPACITOR"
"2","(-7250,5450)","0","passive","I63";
;
$LOCATION"C233"
CDS_LOCATION"C233"
$SEC"1"
CDS_SEC"1"
VOLTAGE"10V"
PACKAGE"0402"
VALUE"0.1UF"
TOLERANCE"10%"
CDS_LIB"passive"
CDS_LMAN_SYM_OUTLINE"-50,0,50,-50"
CLS_PN"G105-0B104-CK";
"2"
$PN"2"12;
"1"
$PN"1"7;
%"CAPACITOR"
"2","(-4150,5400)","0","passive","I64";
;
$LOCATION"C237"
CDS_LOCATION"C237"
$SEC"1"
CDS_SEC"1"
VOLTAGE"10V"
PACKAGE"0402"
VALUE"0.1UF"
CLS_PN"G105-0B104-CK"
CDS_LMAN_SYM_OUTLINE"-50,0,50,-50"
CDS_LIB"passive"
TOLERANCE"10%";
"2"
$PN"2"11;
"1"
$PN"1"10;
%"GND_SG"
"1","(-4450,6100)","0","cls","I65";
;
HDL_POWER"SG"
CDS_LIB"cls"
CDS_LMAN_SYM_OUTLINE"0,0,100,-50"
BODY_TYPE"PLUMBING";
"SGND"2;
%"CAPACITOR"
"2","(-4400,6400)","0","passive","I66";
;
$LOCATION"C236"
CDS_LOCATION"C236"
$SEC"1"
CDS_SEC"1"
VALUE"0.1UF"
VOLTAGE"25V"
PACKAGE"0402"
TOLERANCE"10%"
CDS_LIB"passive"
CDS_LMAN_SYM_OUTLINE"-50,0,50,-50"
CLS_PN"G105-0B104-EK";
"2"
$PN"2"2;
"1"
$PN"1"25;
%"RESISTOR"
"2","(-8600,7150)","0","passive","I67";
;
$LOCATION"R260"
CDS_LOCATION"R260"
$SEC"1"
CDS_SEC"1"
PACKAGE"0402"
VALUE"1KOHM"
NO_ASSY"TRUE"
CDS_LIB"passive"
CDS_LMAN_SYM_OUTLINE"-50,50,50,-100"
CLS_PN"G155-11001-01"
TOLERANCE"1%";
"1"
$PN"1"1;
"2"
$PN"2"30;
%"RESISTOR"
"2","(-6100,7000)","0","passive","I69";
;
$LOCATION"R295"
CDS_LOCATION"R295"
$SEC"1"
CDS_SEC"1"
NO_ASSY"TRUE"
PACKAGE"0402"
VALUE"10KOHM"
CDS_LMAN_SYM_OUTLINE"-50,50,50,-100"
CDS_LIB"passive"
CLS_PN"G155-11002-01"
TOLERANCE"1%";
"1"
$PN"1"4;
"2"
$PN"2"33;
%"CAPACITOR"
"2","(-3100,5400)","0","passive","I71";
;
$LOCATION"C240"
CDS_LOCATION"C240"
$SEC"1"
CDS_SEC"1"
VALUE"22UF"
NO_ASSY"TRUE"
VOLTAGE"10V"
PACKAGE"0805"
CDS_LIB"passive"
CDS_LMAN_SYM_OUTLINE"-50,0,50,-50"
CLS_PN"G107-0F226-CM"
TOLERANCE"20%";
"2"
$PN"2"11;
"1"
$PN"1"10;
%"CAPACITOR"
"2","(-2650,5400)","0","passive","I72";
;
$LOCATION"C241"
CDS_LOCATION"C241"
$SEC"1"
CDS_SEC"1"
VALUE"22UF"
VOLTAGE"10V"
PACKAGE"0805"
CDS_LIB"passive"
CDS_LMAN_SYM_OUTLINE"-50,0,50,-50"
CLS_PN"G107-0F226-CM"
TOLERANCE"20%";
"2"
$PN"2"11;
"1"
$PN"1"10;
%"GND_SG"
"1","(-2250,4900)","0","cls","I73";
;
HDL_POWER"SG"
CDS_LIB"cls"
CDS_LMAN_SYM_OUTLINE"0,0,100,-50"
BODY_TYPE"PLUMBING";
"SGND"11;
%"CAPACITOR"
"2","(-2200,5400)","0","passive","I74";
;
$LOCATION"C243"
CDS_LOCATION"C243"
$SEC"1"
CDS_SEC"1"
VALUE"22UF"
VOLTAGE"10V"
PACKAGE"0805"
CLS_PN"G107-0F226-CM"
CDS_LMAN_SYM_OUTLINE"-50,0,50,-50"
CDS_LIB"passive"
TOLERANCE"20%";
"2"
$PN"2"11;
"1"
$PN"1"10;
%"VCC"
"1","(-2250,5950)","0","cls","I75";
;
VOLTAGE"3.3V"
HDL_POWER"XP3R3V_FPGA"
CDS_LMAN_SYM_OUTLINE"-250,250,250,-250"
CDS_LIB"cls"
BODY_TYPE"PLUMBING";
"$PIN0"10;
%"NCP45560IMNTWG_H_DFN12"
"2","(-5700,5050)","0","analog","I76";
;
$LOCATION"U22"
CDS_LOCATION"U22"
$SEC"2"
CDS_SEC"2"
CLS_PN"G222-10203-01"
CDS_LMAN_SYM_OUTLINE"0,0,400,-500"
CDS_LIB"analog";
"GND"
$PN"4"9;
"VCC"
$PN"3"8;
%"GND_SG"
"1","(-5550,4300)","0","cls","I77";
;
HDL_POWER"SG"
CDS_LMAN_SYM_OUTLINE"0,0,100,-50"
CDS_LIB"cls"
BODY_TYPE"PLUMBING";
"SGND"9;
%"CAPACITOR"
"2","(-5000,4850)","0","passive","I80";
;
$LOCATION"C235"
CDS_LOCATION"C235"
$SEC"1"
CDS_SEC"1"
VALUE"0.1UF"
PACKAGE"0402"
VOLTAGE"10V"
CLS_PN"G105-0B104-CK"
CDS_LMAN_SYM_OUTLINE"-50,0,50,-50"
CDS_LIB"passive"
TOLERANCE"10%";
"2"
$PN"2"9;
"1"
$PN"1"8;
%"CAPACITOR"
"2","(-3650,5400)","0","passive","I81";
;
$LOCATION"C238"
CDS_LOCATION"C238"
$SEC"1"
CDS_SEC"1"
VALUE"22UF"
NO_ASSY"TRUE"
PACKAGE"0805"
VOLTAGE"10V"
TOLERANCE"20%"
CDS_LIB"passive"
CDS_LMAN_SYM_OUTLINE"-50,0,50,-50"
CLS_PN"G107-0F226-CM";
"2"
$PN"2"11;
"1"
$PN"1"10;
%"NCP45560IMNTWG_H_DFN12"
"1","(-5850,6700)","0","analog","I82";
;
$LOCATION"U22"
CDS_LOCATION"U22"
$SEC"1"
CDS_SEC"1"
CLS_PN"G222-10203-01"
PART_NUMBER"NCP45560-H"
CDS_LMAN_SYM_OUTLINE"0,0,800,-1000"
CDS_LIB"analog";
"VIN_2"
$PN"13"7;
"VOUT_5"
$PN"12"10;
"VOUT_4"
$PN"11"10;
"VOUT_3"
$PN"10"10;
"VOUT_2"
$PN"9"10;
"VOUT_1"
$PN"8"10;
"BLEED"
$PN"7"10;
"PG"
$PN"6"33;
"SR"
$PN"5"25;
"EN"
$PN"2"30;
"VIN_1"
$PN"1"7;
%"VCC"
"1","(-8650,7550)","0","cls","I83";
;
HDL_POWER"XP3R3V"
VOLTAGE"3.3"
CDS_LIB"cls"
CDS_LMAN_SYM_OUTLINE"-250,250,250,-250"
BODY_TYPE"PLUMBING";
"$PIN0"1;
%"VCC"
"1","(-5550,5400)","0","cls","I85";
;
VOLTAGE"3.3"
HDL_POWER"XP3R3V"
CDS_LIB"cls"
CDS_LMAN_SYM_OUTLINE"-250,250,250,-250"
BODY_TYPE"PLUMBING";
"$PIN0"8;
%"VCC"
"1","(-8150,5950)","0","cls","I86";
;
HDL_POWER"XP3R3V"
VOLTAGE"3.3"
CDS_LMAN_SYM_OUTLINE"-250,250,250,-250"
CDS_LIB"cls"
BODY_TYPE"PLUMBING";
"$PIN0"7;
%"CAPACITOR"
"2","(-9200,6250)","0","passive","I87";
;
$LOCATION"C229"
CDS_LOCATION"C229"
$SEC"1"
CDS_SEC"1"
VOLTAGE"10V"
VALUE"0.1UF"
PACKAGE"0402"
TOLERANCE"10%"
CLS_PN"G105-0B104-CK"
CDS_LMAN_SYM_OUTLINE"-50,0,50,-50"
CDS_LIB"passive";
"2"
$PN"2"13;
"1"
$PN"1"30;
END.
